# S9S_MB_2U (Grand Teton) — schematic netlist excerpt (pin names and nets, part order shuffled) for the footprints in the layout excerpt that follows; sources: Cadence DE-HDL packaged netlist, KiCad conversion of 03242023_DA0F0TMBIJ0_F0T_Motherboard_J_brd_V01_OCP.brd

PR1334  Q_RES  0 5% CHIP  pkg 0402LF  page 290 : A = PVCCFA_EHV_FIVRA_CPU1_VOS4 ; B = PVCCFA_EHV_FIVRA_CPU1
R3111  Q_RES  0 5% CHIP  pkg 0402LF  page 234 : A = I3C_BMC_SWB_SDA ; B = I3C_BMC_SWB_R_SDA
PC1671  Q_CAP  22UF 16V 20% X6S  pkg C0805  page 271 : A = SW_P12V_PVCCFA_EHV_FIVRA_CPU0_L ; B = GND

(kicad_pcb
	(version 20260206)
	(generator "pcbnew")
	(generator_version "10.0")
	(general
		(thickness 1.6)
		(legacy_teardrops no)
	)
	(paper "A4")
	(title_block
		(title "03242023_DA0F0TMBIJ0_F0T_Motherboard_J_brd_V01_OCP.brd")
		(comment 1 "Grand Teton / footprints 4588-4590 of 6105")
	)
	(layers
		(0 "F.Cu" signal "TOP")
		(4 "In1.Cu" signal "GND")
		(6 "In2.Cu" signal "IN1")
		(8 "In3.Cu" signal "GND1")
		(10 "In4.Cu" signal "IN2")
		(12 "In5.Cu" signal "GND2")
		(14 "In6.Cu" signal "IN3")
		(16 "In7.Cu" signal "GND3")
		(18 "In8.Cu" signal "VCC")
		(20 "In9.Cu" signal "VCC1")
		(22 "In10.Cu" signal "GND4")
		(24 "In11.Cu" signal "IN4")
		(26 "In12.Cu" signal "GND5")
		(28 "In13.Cu" signal "IN5")
		(30 "In14.Cu" signal "GND6")
		(32 "In15.Cu" signal "IN6")
		(34 "In16.Cu" signal "GND7")
		(2 "B.Cu" signal "BOTTOM")
		(9 "F.Adhes" user "F.Adhesive")
		(11 "B.Adhes" user "B.Adhesive")
		(13 "F.Paste" user "Package Geometry/Pastemask Top")
		(15 "B.Paste" user "Package Geometry/Pastemask Bottom")
		(5 "F.SilkS" user "Ref Des/Silkscreen Top")
		(7 "B.SilkS" user "Ref Des/Silkscreen Bottom")
		(1 "F.Mask" user "Board Geometry/Soldermask Top")
		(3 "B.Mask" user "Board Geometry/Soldermask Bottom")
		(17 "Dwgs.User" user "User.Drawings")
		(19 "Cmts.User" user "User.Comments")
		(21 "Eco1.User" user "User.Eco1")
		(23 "Eco2.User" user "User.Eco2")
		(25 "Edge.Cuts" user "Board Geometry/Outline")
		(27 "Margin" user)
		(31 "F.CrtYd" user "Package Geometry/Place Bound Top")
		(29 "B.CrtYd" user "Package Geometry/Place Bound Bottom")
		(35 "F.Fab" user "Ref Des/Assembly Top")
		(33 "B.Fab" user "Ref Des/Assembly Bottom")
	)
	(footprint ""
		(layer "B.Cu")
		(at 293.053516 -367.168176 180)
		(property "Reference" "PC1671"
			(at 0 0 0)
			(layer "B.SilkS")
			(hide yes)
			(effects
				(font
					(size 1.27 1.27)
				)
				(justify mirror)
			)
		)
		(property "Value" ""
			(at 0 0 0)
			(layer "B.Fab")
			(effects
				(font
					(size 1.27 1.27)
				)
				(justify mirror)
			)
		)
		(duplicate_pad_numbers_are_jumpers no)
		(fp_line
			(start 1.524 0.762)
			(end 1.524 -0.762)
			(stroke
				(width 0.1524)
				(type default)
			)
			(layer "B.SilkS")
		)
		(fp_line
			(start 1.524 -0.762)
			(end -1.524 -0.762)
			(stroke
				(width 0.1524)
				(type default)
			)
			(layer "B.SilkS")
		)
		(fp_line
			(start -1.524 0.762)
			(end 1.524 0.762)
			(stroke
				(width 0.1524)
				(type default)
			)
			(layer "B.SilkS")
		)
		(fp_line
			(start -1.524 -0.762)
			(end -1.524 0.762)
			(stroke
				(width 0.1524)
				(type default)
			)
			(layer "B.SilkS")
		)
		(fp_line
			(start 1.1049 0.724916)
			(end -1.1049 0.724916)
			(stroke
				(width 0.1)
				(type default)
			)
			(layer "B.Fab")
		)
		(fp_line
			(start 1.1049 -0.724916)
			(end 1.1049 0.724916)
			(stroke
				(width 0.1)
				(type default)
			)
			(layer "B.Fab")
		)
		(fp_line
			(start -1.1049 0.724916)
			(end -1.1049 -0.724916)
			(stroke
				(width 0.1)
				(type default)
			)
			(layer "B.Fab")
		)
		(fp_line
			(start -1.1049 -0.724916)
			(end 1.1049 -0.724916)
			(stroke
				(width 0.1)
				(type default)
			)
			(layer "B.Fab")
		)
		(pad "1" smd rect
			(at 0.889 0 180)
			(size 1.016 1.27)
			(layers "B.Cu" "B.Mask" "B.Paste")
			(net "SW_P12V_PVCCFA_EHV_FIVRA_CPU0_L")
		)
		(pad "2" smd rect
			(at -0.889 0 180)
			(size 1.016 1.27)
			(layers "B.Cu" "B.Mask" "B.Paste")
			(net "GND")
		)
	)
	(footprint ""
		(layer "B.Cu")
		(at 172.346112 -8.907018)
		(property "Reference" "R3111"
			(at 0 0 0)
			(layer "B.SilkS")
			(hide yes)
			(effects
				(font
					(size 1.27 1.27)
				)
				(justify mirror)
			)
		)
		(property "Value" ""
			(at 0 0 0)
			(layer "B.Fab")
			(effects
				(font
					(size 1.27 1.27)
				)
				(justify mirror)
			)
		)
		(duplicate_pad_numbers_are_jumpers no)
		(fp_line
			(start -0.7874 -0.4064)
			(end -0.7874 0.4064)
			(stroke
				(width 0.1524)
				(type default)
			)
			(layer "B.SilkS")
		)
		(fp_line
			(start -0.7874 0.4064)
			(end 0.7874 0.4064)
			(stroke
				(width 0.1524)
				(type default)
			)
			(layer "B.SilkS")
		)
		(fp_line
			(start 0.7874 -0.4064)
			(end -0.7874 -0.4064)
			(stroke
				(width 0.1524)
				(type default)
			)
			(layer "B.SilkS")
		)
		(fp_line
			(start 0.7874 0.4064)
			(end 0.7874 -0.4064)
			(stroke
				(width 0.1524)
				(type default)
			)
			(layer "B.SilkS")
		)
		(fp_line
			(start -0.67945 -0.3048)
			(end -0.67945 0.3048)
			(stroke
				(width 0.1)
				(type default)
			)
			(layer "B.Fab")
		)
		(fp_line
			(start -0.67945 0.3048)
			(end -0.120396 0.3048)
			(stroke
				(width 0.1)
				(type default)
			)
			(layer "B.Fab")
		)
		(fp_line
			(start -0.12065 -0.3048)
			(end -0.67945 -0.3048)
			(stroke
				(width 0.1)
				(type default)
			)
			(layer "B.Fab")
		)
		(fp_line
			(start -0.12065 -0.2794)
			(end -0.12065 -0.3048)
			(stroke
				(width 0.1)
				(type default)
			)
			(layer "B.Fab")
		)
		(fp_line
			(start -0.120396 0.2794)
			(end 0.12065 0.2794)
			(stroke
				(width 0.1)
				(type default)
			)
			(layer "B.Fab")
		)
		(fp_line
			(start -0.120396 0.3048)
			(end -0.120396 0.2794)
			(stroke
				(width 0.1)
				(type default)
			)
			(layer "B.Fab")
		)
		(fp_line
			(start 0.12065 -0.305054)
			(end 0.12065 -0.2794)
			(stroke
				(width 0.1)
				(type default)
			)
			(layer "B.Fab")
		)
		(fp_line
			(start 0.12065 -0.2794)
			(end -0.12065 -0.2794)
			(stroke
				(width 0.1)
				(type default)
			)
			(layer "B.Fab")
		)
		(fp_line
			(start 0.12065 0.2794)
			(end 0.12065 0.3048)
			(stroke
				(width 0.1)
				(type default)
			)
			(layer "B.Fab")
		)
		(fp_line
			(start 0.12065 0.3048)
			(end 0.67945 0.3048)
			(stroke
				(width 0.1)
				(type default)
			)
			(layer "B.Fab")
		)
		(fp_line
			(start 0.67945 -0.305054)
			(end 0.12065 -0.305054)
			(stroke
				(width 0.1)
				(type default)
			)
			(layer "B.Fab")
		)
		(fp_line
			(start 0.67945 0.3048)
			(end 0.67945 -0.305054)
			(stroke
				(width 0.1)
				(type default)
			)
			(layer "B.Fab")
		)
		(pad "1" smd circle
			(at 0.40005 0 180)
			(size 0 0)
			(layers "B.Cu" "B.Mask" "B.Paste")
			(net "I3C_BMC_SWB_SDA")
		)
		(pad "2" smd circle
			(at -0.40005 0 180)
			(size 0 0)
			(layers "B.Cu" "B.Mask" "B.Paste")
			(net "I3C_BMC_SWB_R_SDA")
		)
	)
	(footprint ""
		(layer "B.Cu")
		(at 38.09746 -357.575612)
		(property "Reference" "PR1334"
			(at 0 0 0)
			(layer "B.SilkS")
			(hide yes)
			(effects
				(font
					(size 1.27 1.27)
				)
				(justify mirror)
			)
		)
		(property "Value" ""
			(at 0 0 0)
			(layer "B.Fab")
			(effects
				(font
					(size 1.27 1.27)
				)
				(justify mirror)
			)
		)
		(duplicate_pad_numbers_are_jumpers no)
		(fp_line
			(start -0.7874 -0.4064)
			(end -0.7874 0.4064)
			(stroke
				(width 0.1524)
				(type default)
			)
			(layer "B.SilkS")
		)
		(fp_line
			(start -0.7874 0.4064)
			(end 0.7874 0.4064)
			(stroke
				(width 0.1524)
				(type default)
			)
			(layer "B.SilkS")
		)
		(fp_line
			(start 0.7874 -0.4064)
			(end -0.7874 -0.4064)
			(stroke
				(width 0.1524)
				(type default)
			)
			(layer "B.SilkS")
		)
		(fp_line
			(start 0.7874 0.4064)
			(end 0.7874 -0.4064)
			(stroke
				(width 0.1524)
				(type default)
			)
			(layer "B.SilkS")
		)
		(fp_line
			(start -0.67945 -0.3048)
			(end -0.67945 0.3048)
			(stroke
				(width 0.1)
				(type default)
			)
			(layer "B.Fab")
		)
		(fp_line
			(start -0.67945 0.3048)
			(end -0.120396 0.3048)
			(stroke
				(width 0.1)
				(type default)
			)
			(layer "B.Fab")
		)
		(fp_line
			(start -0.12065 -0.3048)
			(end -0.67945 -0.3048)
			(stroke
				(width 0.1)
				(type default)
			)
			(layer "B.Fab")
		)
		(fp_line
			(start -0.12065 -0.2794)
			(end -0.12065 -0.3048)
			(stroke
				(width 0.1)
				(type default)
			)
			(layer "B.Fab")
		)
		(fp_line
			(start -0.120396 0.2794)
			(end 0.12065 0.2794)
			(stroke
				(width 0.1)
				(type default)
			)
			(layer "B.Fab")
		)
		(fp_line
			(start -0.120396 0.3048)
			(end -0.120396 0.2794)
			(stroke
				(width 0.1)
				(type default)
			)
			(layer "B.Fab")
		)
		(fp_line
			(start 0.12065 -0.305054)
			(end 0.12065 -0.2794)
			(stroke
				(width 0.1)
				(type default)
			)
			(layer "B.Fab")
		)
		(fp_line
			(start 0.12065 -0.2794)
			(end -0.12065 -0.2794)
			(stroke
				(width 0.1)
				(type default)
			)
			(layer "B.Fab")
		)
		(fp_line
			(start 0.12065 0.2794)
			(end 0.12065 0.3048)
			(stroke
				(width 0.1)
				(type default)
			)
			(layer "B.Fab")
		)
		(fp_line
			(start 0.12065 0.3048)
			(end 0.67945 0.3048)
			(stroke
				(width 0.1)
				(type default)
			)
			(layer "B.Fab")
		)
		(fp_line
			(start 0.67945 -0.305054)
			(end 0.12065 -0.305054)
			(stroke
				(width 0.1)
				(type default)
			)
			(layer "B.Fab")
		)
		(fp_line
			(start 0.67945 0.3048)
			(end 0.67945 -0.305054)
			(stroke
				(width 0.1)
				(type default)
			)
			(layer "B.Fab")
		)
		(pad "1" smd circle
			(at 0.40005 0 180)
			(size 0 0)
			(layers "B.Cu" "B.Mask" "B.Paste")
			(net "PVCCFA_EHV_FIVRA_CPU1_VOS4")
		)
		(pad "2" smd circle
			(at -0.40005 0 180)
			(size 0 0)
			(layers "B.Cu" "B.Mask" "B.Paste")
			(net "PVCCFA_EHV_FIVRA_CPU1")
		)
	)
)
